ExaMAX CONN
J112/J111 J110/J109 Power CONN
J45
ExaMAX CONN
J108/J107 J106/J105
CPU1 U26 CPU0 U25
DIMM *6DIMM *6 DIMM *6 DIMM *6
M.2 Conn J59
OCP NIC1
J35
OCP NIC0
J38
SCM
J41
E1S
J90